FILE_TYPE = CONNECTIVITY;
{Allegro Design Entry HDL 17.2-2016 S081 (4005846) 1/11/2022}
"PAGE_NUMBER" = 286;
0"NC";
1"PVNN_MAIN_CPU1\g";
2"PVNN_MAIN_CPU1\g";
3"P3V3_AUX\g";
4"SW_P12V_PVCCINFAON_CPU1_FLT\g";
5"P3V3_AUX\g";
6"P3V3_AUX\g";
7"GND\g";
8"GND\g";
9"GND\g";
10"GND\g";
11"GND\g";
12"GND\g";
13"GND\g";
14"GND\g";
15"GND\g";
16"GND\g";
17"PVNN_MAIN_CPU1_VCC";
18"SW_PVNN_MAIN_CPU1_BST_R";
19"PVNN_MAIN_CPU1_FB_RC";
20"PVNN_MAIN_CPU1_FB";
21"PWRGD_PVNN_MAIN_CPU1";
22"SW_PVNN_MAIN_CPU1_SW";
23"PWRGD_PVNN_MAIN_CPU1_R";
24"SW_PVNN_MAIN_CPU1_BST";
25"PVNN_MAIN_CPU1_REF";
26"PVNN_MAIN_CPU1_CS";
27"PVNN_MAIN_CPU1_MODE";
28"FM_PVNN_MAIN_CPU1_EN";
%"Q_CAP"
"1","(3625,6100)","0","pure_quanta","I10";
;
PART_NUMBER"CH5104KEB02"
TOLERANCE"10%"
MATERIAL"X6S"
VOLTAGE"25V"
VALUE"1UF"
PACK_TYPE"C0402"
LOCATION"PC2222"
CDS_LIB"pure_quanta"
SEC_TYPE"C0402"
SEC"1";
"B"
$PN"2"16;
"A"
$PN"1"17;
%"UNIVERSAL_GND"
"1","(3200,6350)","0","logical_power","I11";
;
HDL_POWER"GND"
CDS_LIB"logical_power";
"A"13;
%"Q_RES"
"2","(3200,6650)","0","pure_quanta","I12";
;
PART_NUMBER"CS36042FB04"
VALUE"60.4K"
WATTAGE"1/16W"
MATERIAL"CHIP"
PACK_TYPE"0402LF"
TOLERANCE"1%"
LOCATION"PR2220"
CDS_LIB"pure_quanta"
$SEC"1"
CDS_SEC"1";
"A"
$PN"1"27;
"B"
$PN"2"13;
%"Q_RES"
"2","(3625,6725)","0","pure_quanta","I13";
;
PART_NUMBER"CS00002JB13"
TOLERANCE"5%"
MATERIAL"CHIP"
VALUE"0"
WATTAGE"1/16W"
PACK_TYPE"0402LF"
LOCATION"PR3338"
CDS_LIB"pure_quanta"
$SEC"1"
CDS_SEC"1";
"A"
$PN"1"5;
"B"
$PN"2"17;
%"Q_CAP"
"1","(2900,7950)","0","pure_quanta","I14";
;
PART_NUMBER"CH6223MEA01"
MATERIAL"X6S"
TOLERANCE"20%"
VOLTAGE"16V"
PACK_TYPE"C0805"
VALUE"22UF"
LOCATION"PC1281"
CDS_LIB"pure_quanta"
BOM_COST"VR_PCH"
$SEC"1"
CDS_SEC"1";
"B"
$PN"2"14;
"A"
$PN"1"4;
%"UNIVERSAL_POWER"
"1","(3625,6900)","0","logical_power","I15";
;
HDL_POWER"P3V3_AUX"
CDS_LIB"logical_power";
"A"5;
%"Q_CAP"
"1","(3325,7950)","0","pure_quanta","I16";
;
PART_NUMBER"CH5103KEB01"
PACK_TYPE"C0402"
TOLERANCE"10%"
VOLTAGE"16V"
MATERIAL"X6S"
VALUE"1UF"
LOCATION"PC1282"
CDS_LIB"pure_quanta"
LOCATION"PC1282"
$SEC"1"
CDS_SEC"1";
"B"
$PN"2"14;
"A"
$PN"1"4;
%"UNIVERSAL_GND"
"1","(4075,5725)","0","logical_power","I17";
;
HDL_POWER"GND"
CDS_LIB"logical_power";
"A"12;
%"UNIVERSAL_GND"
"1","(5400,5625)","0","logical_power","I18";
;
HDL_POWER"GND"
CDS_LIB"logical_power";
"A"11;
%"Q_RES"
"2","(4075,6050)","0","pure_quanta","I19";
;
PART_NUMBER"CS33482FB04"
TOLERANCE"1%"
VALUE"34.8K"
WATTAGE"1/16W"
PACK_TYPE"0402LF"
MATERIAL"CHIP"
LOCATION"PR2222"
CDS_LIB"pure_quanta"
$SEC"1"
CDS_SEC"1";
"A"
$PN"1"26;
"B"
$PN"2"12;
%"VCCAUX15"
"1","(1200,7500)","0","logical_power","I2";
;
HDL_POWER"P3V3_AUX"
CDS_LIB"logical_power"
BOM_COST"VR_PCH";
"A"6;
%"RS53317LR"
"1","(4950,7050)","0","pure_quanta","I20";
;
PART_NUMBER"AL053317005"
VALUE"RS53317LR"
PART_TYPE"SMLF"
MATERIAL"IC"
LOCATION"PU82"
CDS_LMAN_SYM_OUTLINE"-250,725,250,-725"
NEEDS_NO_SIZE"TRUE"
CDS_LIB"pure_quanta"
SEC_TYPE""
SEC"1";
"SW1"
$PN"2"22;
"CS"
$PN"4"26;
"MODE"
$PN"12"27;
"REF"
$PN"8"25;
"SW2"
$PN"11"22;
"PGND1"
$PN"1"10;
"VCC"
$PN"13"17;
"AGND"
$PN"7"11;
"FB"
$PN"6"20;
"BST"
$PN"10"24;
"EN"
$PN"5"28;
"PGND2"
$PN"14"10;
"PGOOD"
$PN"9"23;
"VIN"
$PN"3"4;
%"UNIVERSAL_GND"
"1","(5550,6125)","0","logical_power","I21";
;
HDL_POWER"GND"
CDS_LIB"logical_power";
"A"10;
%"Q_RES"
"1","(6475,5750)","0","pure_quanta","I22";
;
PART_NUMBER"CS00002JB13"
WATTAGE"1/16W"
MATERIAL"CHIP"
TOLERANCE"5%"
VALUE"0"
PACK_TYPE"0402LF"
LOCATION"PR2"
CDS_LIB"pure_quanta"
$SEC"1"
CDS_SEC"1";
"B"
$PN"2"7;
"A"
$PN"1"11;
%"Q_CAP"
"1","(6025,6050)","0","pure_quanta","I23";
;
PART_NUMBER"TMP_QCH2336K1B12"
TOLERANCE"10%"
MATERIAL"X7R"
PACK_TYPE"0402"
VOLTAGE"50V"
VALUE"3300PF"
LOCATION"PC28"
CDS_LIB"pure_quanta"
$SEC"1"
CDS_SEC"1";
"B"
$PN"2"11;
"A"
$PN"1"25;
%"Q_CAP"
"1","(6700,7375)","0","pure_quanta","I24";
;
PART_NUMBER"CH4224K1B01"
VOLTAGE"25V"
TOLERANCE"10%"
VALUE"0.22UF"
MATERIAL"X7R"
PACK_TYPE"C0402"
LOCATION"PC1283"
CDS_LIB"pure_quanta"
$SEC"1"
CDS_SEC"1";
"B"
$PN"2"22;
"A"
$PN"1"18;
%"Q_RES"
"1","(6375,7525)","0","pure_quanta","I25";
;
PART_NUMBER"CS00002JB13"
MATERIAL"CHIP"
PACK_TYPE"0402LF"
TOLERANCE"5%"
VALUE"0"
LOCATION"PR4272"
WATTAGE"1/16W"
SEC_TYPE"0402LF"
CDS_LIB"pure_quanta"
SEC"1";
"B"
$PN"2"18;
"A"
$PN"1"24;
%"Q_RES"
"2","(7075,6050)","0","pure_quanta","I26";
;
PART_NUMBER"CS31242BB10"
WATTAGE"1/16W"
TOLERANCE"0.1%"
VALUE"12.4K"
PACK_TYPE"0402LF"
MATERIAL"CHIP"
LOCATION"PR51"
SEC_TYPE"0402LF"
CDS_LIB"pure_quanta"
SEC"1";
"A"
$PN"1"20;
"B"
$PN"2"7;
%"Q_INDUCTOR"
"1","(7300,7250)","0","pure_quanta","I27";
;
PART_NUMBER"CV-4755MZ12"
VALUE"4.7UH"
MATERIAL"IND"
PACK_TYPE"SMLF"
LOCATION"PL121"
BOM_COST"VR_PCH"
CDS_LIB"pure_quanta"
NEEDS_NO_SIZE"TRUE"
$SEC"1"
CDS_SEC"1";
"1"
$PN"1"22;
"2"
$PN"2"1;
%"Q_CAP"
"1","(7725,7025)","0","pure_quanta","I28";
;
PART_NUMBER"CH4106K1B01"
VOLTAGE"50V"
TOLERANCE"10%"
MATERIAL"X7R"
VALUE"100NF"
PACK_TYPE"C0402"
LOCATION"PC1284"
CDS_LIB"pure_quanta"
$SEC"1"
CDS_SEC"1";
"B"
$PN"2"8;
"A"
$PN"1"1;
%"Q_RES"
"1","(7375,7725)","0","pure_quanta","I29";
;
PART_NUMBER"CS00002JB13"
VALUE"0"
TOLERANCE"5%"
PACK_TYPE"0402LF"
MATERIAL"CHIP"
LOCATION"R2387"
WATTAGE"1/16W"
CDS_LIB"pure_quanta"
$SEC"1"
CDS_SEC"1";
"B"
$PN"2"21;
"A"
$PN"1"23;
%"UNIVERSAL_GND"
"1","(3625,5725)","0","logical_power","I3";
;
HDL_POWER"GND"
CDS_LIB"logical_power";
"A"16;
%"VCCAUX15"
"1","(2450,8400)","0","logical_power","I30";
;
HDL_POWER"SW_P12V_PVCCINFAON_CPU1_FLT"
CDS_LIB"logical_power"
BOM_COST"VR_PCH";
"A"4;
%"Q_RES"
"2","(6350,8075)","0","pure_quanta","I31";
;
PART_NUMBER"CS31002FB08"
TOLERANCE"1%"
MATERIAL"CHIP"
PACK_TYPE"0402LF"
VALUE"10K"
WATTAGE"1/16W"
LOCATION"R2584"
BOM_COST"VR_PCH"
CDS_LIB"pure_quanta"
$SEC"1"
CDS_SEC"1";
"A"
$PN"1"3;
"B"
$PN"2"23;
%"UNIVERSAL_POWER"
"1","(6350,8325)","0","logical_power","I32";
;
HDL_POWER"P3V3_AUX"
CDS_LIB"logical_power";
"A"3;
%"Q_CAP"
"2","(8075,6025)","0","pure_quanta","I33";
;
PART_NUMBER"TMP_QCH16806KB17"
MATERIAL"X7R"
VOLTAGE"50V"
VALUE"680PF"
TOLERANCE"10%"
PACK_TYPE"0402"
LOCATION"PC238"
CDS_LIB"pure_quanta"
$SEC"1"
CDS_SEC"1";
"A"
$PN"1"20;
"B"
$PN"2"19;
%"Q_RES"
"1","(8075,6375)","0","pure_quanta","I34";
;
PART_NUMBER"CS28252BB01"
VALUE"8.25K"
WATTAGE"1/16W"
PACK_TYPE"0402LF"
TOLERANCE"0.1%"
MATERIAL"CHIP"
LOCATION"PR502"
CDS_LIB"pure_quanta"
$SEC"1"
CDS_SEC"1";
"B"
$PN"2"19;
"A"
$PN"1"20;
%"UNIVERSAL_GND"
"1","(7875,7325)","0","logical_power","I35";
;
HDL_POWER"GND"
CDS_LIB"logical_power";
"A"9;
%"Q_CAP"
"1","(8125,7025)","0","pure_quanta","I36";
;
PART_NUMBER"CH622KMEA03"
PACK_TYPE"C0805"
MATERIAL"X6S"
VALUE"22UF"
VOLTAGE"4V"
TOLERANCE"20%"
LOCATION"PC1285"
CDS_LIB"pure_quanta"
BOM_COST"VR_PCH"
$SEC"1"
CDS_SEC"1";
"B"
$PN"2"8;
"A"
$PN"1"1;
%"Q_CAP"
"1","(7875,7550)","0","pure_quanta","I37";
;
PART_NUMBER"TMP_QCH21006JB10"
PACK_TYPE"0402"
VALUE"1000PF"
VOLTAGE"50V"
TOLERANCE"5%"
MATERIAL"X7R"
LOCATION"C1297"
CDS_LIB"pure_quanta"
$SEC"1"
CDS_SEC"1";
"B"
$PN"2"9;
"A"
$PN"1"21;
%"Q_CAP"
"1","(8500,7025)","0","pure_quanta","I38";
;
PART_NUMBER"CH622KMEA03"
VALUE"22UF"
VOLTAGE"4V"
MATERIAL"X6S"
TOLERANCE"20%"
PACK_TYPE"C0805"
LOCATION"PC1286"
CDS_LIB"pure_quanta"
BOM_COST"VR_PCH"
$SEC"1"
CDS_SEC"1";
"B"
$PN"2"8;
"A"
$PN"1"1;
%"UNIVERSAL_GND"
"1","(2500,6800)","0","logical_power","I4";
;
HDL_POWER"GND"
CDS_LIB"logical_power";
"A"15;
%"Q_CAP"
"1","(8775,6100)","0","pure_quanta","I40";
;
PART_NUMBER"TMP_QCH31004KB17"
VALUE"0.01UF"
TOLERANCE"10%"
PACK_TYPE"0402"
VOLTAGE"25V"
MATERIAL"X7R"
LOCATION"PC2277"
CDS_LIB"pure_quanta"
$SEC"1"
CDS_SEC"1";
"B"
$PN"2"7;
"A"
$PN"1"19;
%"UNIVERSAL_GND"
"1","(8875,6650)","0","logical_power","I41";
;
CDS_LIB"logical_power"
HDL_POWER"GND";
"A"8;
%"Q_RES"
"1","(9400,6125)","0","pure_quanta","I42";
;
PART_NUMBER"CS00002JB13"
PACK_TYPE"0402LF"
MATERIAL"EMPTY"
TOLERANCE"5%"
VALUE"0"
LOCATION"PR4700"
CDS_LIB"pure_quanta"
WATTAGE"1/16W"
$SEC"1"
CDS_SEC"1";
"B"
$PN"2"2;
"A"
$PN"1"19;
%"Q_RES"
"1","(9400,6375)","0","pure_quanta","I43";
;
PART_NUMBER"CS00002JB13"
TOLERANCE"5%"
VALUE"0"
MATERIAL"CHIP"
PACK_TYPE"0402LF"
LOCATION"PR4699"
WATTAGE"1/16W"
CDS_LIB"pure_quanta"
$SEC"1"
CDS_SEC"1";
"B"
$PN"2"1;
"A"
$PN"1"19;
%"Q_CAP"
"1","(8875,7025)","0","pure_quanta","I44";
;
PART_NUMBER"CH622KMEA03"
MATERIAL"X6S"
VALUE"22UF"
VOLTAGE"4V"
TOLERANCE"20%"
PACK_TYPE"C0805"
LOCATION"PC1287"
CDS_LIB"pure_quanta"
BOM_COST"VR_PCH"
$SEC"1"
CDS_SEC"1";
"B"
$PN"2"8;
"A"
$PN"1"1;
%"Q_CAP"
"1","(9250,7025)","0","pure_quanta","I45";
;
PART_NUMBER"CH622KMEA03"
MATERIAL"X6S"
TOLERANCE"20%"
VOLTAGE"4V"
VALUE"22UF"
PACK_TYPE"C0805"
LOCATION"PC1207"
CDS_LIB"pure_quanta"
BOM_COST"VR_PCH"
$SEC"1"
CDS_SEC"1";
"B"
$PN"2"8;
"A"
$PN"1"1;
%"UNIVERSAL_GND"
"1","(9925,5450)","0","logical_power","I46";
;
CDS_LIB"logical_power"
HDL_POWER"GND";
"A"7;
%"UNIVERSAL_POWER"
"1","(9950,6225)","0","logical_power","I47";
;
HDL_POWER"PVNN_MAIN_CPU1"
CDS_LIB"logical_power";
"A"2;
%"UNIVERSAL_POWER"
"1","(9950,7400)","0","logical_power","I48";
;
HDL_POWER"PVNN_MAIN_CPU1"
CDS_LIB"logical_power";
"A"1;
%"Q_RES"
"1","(1925,7400)","0","pure_quanta","I5";
;
PART_NUMBER"CS31002FB08"
TOLERANCE"1%"
MATERIAL"EMPTY"
PACK_TYPE"0402LF"
WATTAGE"1/16W"
VALUE"10K"
LOCATION"R2384"
CDS_LIB"pure_quanta"
$SEC"1"
CDS_SEC"1";
"B"
$PN"2"28;
"A"
$PN"1"6;
%"Q_CAP"
"1","(2400,7025)","2","pure_quanta","I6";
;
PART_NUMBER"TMP_QCH21006JB10"
VOLTAGE"50V"
VALUE"1000PF"
TOLERANCE"5%"
MATERIAL"EMPTY"
PACK_TYPE"0402"
LOCATION"C1308"
CDS_LIB"pure_quanta"
$SEC"1"
CDS_SEC"1";
"B"
$PN"2"15;
"A"
$PN"1"28;
%"Q_RES"
"2","(2500,7025)","0","pure_quanta","I7";
;
PART_NUMBER"CS22002FB07"
VALUE"2K"
MATERIAL"CHIP"
PACK_TYPE"0402LF"
WATTAGE"1/16W"
TOLERANCE"1%"
LOCATION"R2385"
CDS_LIB"pure_quanta"
$SEC"1"
CDS_SEC"1";
"A"
$PN"1"28;
"B"
$PN"2"15;
%"UNIVERSAL_GND"
"1","(2450,7600)","0","logical_power","I8";
;
HDL_POWER"GND"
CDS_LIB"logical_power";
"A"14;
%"Q_CAP"
"1","(2450,7950)","0","pure_quanta","I9";
;
PART_NUMBER"CH6223MEA01"
PACK_TYPE"C0805"
MATERIAL"X6S"
VALUE"22UF"
VOLTAGE"16V"
TOLERANCE"20%"
LOCATION"PC1280"
CDS_LIB"pure_quanta"
BOM_COST"VR_PCH"
$SEC"1"
CDS_SEC"1";
"B"
$PN"2"14;
"A"
$PN"1"4;
END.
